# SCM (Grand Teton) — schematic netlist excerpt (pin names and nets, part order shuffled) for the footprints in the layout excerpt that follows; sources: Cadence DE-HDL packaged netlist, KiCad conversion of 12092022_DA0F0TMDCD0_F0T_Management_Board_D_brd_V3_OCP.brd

R667  Q_RES  4.7K 1% CHIP  pkg 0402LF  page 28 : A = P3V3_AUX ; B = LED_POSTCODE_INT
R195  Q_RES  1K 1% CHIP  pkg 0402LF  page 14 : A = P1V2_P1V0_I3C_VDDL1 ; B = I3C1_SPD_SDA

(kicad_pcb
	(version 20260206)
	(generator "pcbnew")
	(generator_version "10.0")
	(general
		(thickness 1.6)
		(legacy_teardrops no)
	)
	(paper "A4")
	(title_block
		(title "12092022_DA0F0TMDCD0_F0T_Management_Board_D_brd_V3_OCP.brd")
		(comment 1 "Grand Teton / footprints 1135-1136 of 1440")
	)
	(layers
		(0 "F.Cu" signal "TOP")
		(4 "In1.Cu" signal "GND")
		(6 "In2.Cu" signal "IN1")
		(8 "In3.Cu" signal "GND1")
		(10 "In4.Cu" signal "IN2")
		(12 "In5.Cu" signal "VCC")
		(14 "In6.Cu" signal "VCC1")
		(16 "In7.Cu" signal "IN3")
		(18 "In8.Cu" signal "GND2")
		(20 "In9.Cu" signal "IN4")
		(22 "In10.Cu" signal "GND3")
		(2 "B.Cu" signal "BOTTOM")
		(9 "F.Adhes" user "F.Adhesive")
		(11 "B.Adhes" user "B.Adhesive")
		(13 "F.Paste" user "Package Geometry/Pastemask Top")
		(15 "B.Paste" user "Package Geometry/Pastemask Bottom")
		(5 "F.SilkS" user "Ref Des/Silkscreen Top")
		(7 "B.SilkS" user "Ref Des/Silkscreen Bottom")
		(1 "F.Mask" user "Board Geometry/Soldermask Top")
		(3 "B.Mask" user "Board Geometry/Soldermask Bottom")
		(17 "Dwgs.User" user "User.Drawings")
		(19 "Cmts.User" user "User.Comments")
		(21 "Eco1.User" user "User.Eco1")
		(23 "Eco2.User" user "User.Eco2")
		(25 "Edge.Cuts" user "Board Geometry/Outline")
		(27 "Margin" user)
		(31 "F.CrtYd" user "Package Geometry/Place Bound Top")
		(29 "B.CrtYd" user "Package Geometry/Place Bound Bottom")
		(35 "F.Fab" user "Ref Des/Assembly Top")
		(33 "B.Fab" user "Ref Des/Assembly Bottom")
	)
	(footprint ""
		(layer "B.Cu")
		(at 63.5762 -93.8022 90)
		(property "Reference" "R667"
			(at 0 0 90)
			(layer "B.SilkS")
			(hide yes)
			(effects
				(font
					(size 1.27 1.27)
				)
				(justify mirror)
			)
		)
		(property "Value" ""
			(at 0 0 90)
			(layer "B.Fab")
			(effects
				(font
					(size 1.27 1.27)
				)
				(justify mirror)
			)
		)
		(duplicate_pad_numbers_are_jumpers no)
		(fp_line
			(start 0.7874 -0.4064)
			(end -0.7874 -0.4064)
			(stroke
				(width 0.1524)
				(type default)
			)
			(layer "B.SilkS")
		)
		(fp_line
			(start -0.7874 -0.4064)
			(end -0.7874 0.4064)
			(stroke
				(width 0.1524)
				(type default)
			)
			(layer "B.SilkS")
		)
		(fp_line
			(start 0.7874 0.4064)
			(end 0.7874 -0.4064)
			(stroke
				(width 0.1524)
				(type default)
			)
			(layer "B.SilkS")
		)
		(fp_line
			(start -0.7874 0.4064)
			(end 0.7874 0.4064)
			(stroke
				(width 0.1524)
				(type default)
			)
			(layer "B.SilkS")
		)
		(fp_line
			(start 0.67945 -0.305054)
			(end 0.12065 -0.305054)
			(stroke
				(width 0.1)
				(type default)
			)
			(layer "B.Fab")
		)
		(fp_line
			(start 0.12065 -0.305054)
			(end 0.12065 -0.2794)
			(stroke
				(width 0.1)
				(type default)
			)
			(layer "B.Fab")
		)
		(fp_line
			(start -0.12065 -0.3048)
			(end -0.67945 -0.3048)
			(stroke
				(width 0.1)
				(type default)
			)
			(layer "B.Fab")
		)
		(fp_line
			(start -0.67945 -0.3048)
			(end -0.67945 0.3048)
			(stroke
				(width 0.1)
				(type default)
			)
			(layer "B.Fab")
		)
		(fp_line
			(start 0.12065 -0.2794)
			(end -0.12065 -0.2794)
			(stroke
				(width 0.1)
				(type default)
			)
			(layer "B.Fab")
		)
		(fp_line
			(start -0.12065 -0.2794)
			(end -0.12065 -0.3048)
			(stroke
				(width 0.1)
				(type default)
			)
			(layer "B.Fab")
		)
		(fp_line
			(start 0.12065 0.2794)
			(end 0.12065 0.3048)
			(stroke
				(width 0.1)
				(type default)
			)
			(layer "B.Fab")
		)
		(fp_line
			(start -0.120396 0.2794)
			(end 0.12065 0.2794)
			(stroke
				(width 0.1)
				(type default)
			)
			(layer "B.Fab")
		)
		(fp_line
			(start 0.67945 0.3048)
			(end 0.67945 -0.305054)
			(stroke
				(width 0.1)
				(type default)
			)
			(layer "B.Fab")
		)
		(fp_line
			(start 0.12065 0.3048)
			(end 0.67945 0.3048)
			(stroke
				(width 0.1)
				(type default)
			)
			(layer "B.Fab")
		)
		(fp_line
			(start -0.120396 0.3048)
			(end -0.120396 0.2794)
			(stroke
				(width 0.1)
				(type default)
			)
			(layer "B.Fab")
		)
		(fp_line
			(start -0.67945 0.3048)
			(end -0.120396 0.3048)
			(stroke
				(width 0.1)
				(type default)
			)
			(layer "B.Fab")
		)
		(pad "1" smd circle
			(at 0.40005 0 270)
			(size 0 0)
			(layers "B.Cu" "B.Mask" "B.Paste")
			(net "P3V3_AUX")
		)
		(pad "2" smd circle
			(at -0.40005 0 270)
			(size 0 0)
			(layers "B.Cu" "B.Mask" "B.Paste")
			(net "LED_POSTCODE_INT")
		)
	)
	(footprint ""
		(layer "B.Cu")
		(at 40.887142 -63.756794 -90)
		(property "Reference" "R195"
			(at 0 0 90)
			(layer "B.SilkS")
			(hide yes)
			(effects
				(font
					(size 1.27 1.27)
				)
				(justify mirror)
			)
		)
		(property "Value" ""
			(at 0 0 90)
			(layer "B.Fab")
			(effects
				(font
					(size 1.27 1.27)
				)
				(justify mirror)
			)
		)
		(duplicate_pad_numbers_are_jumpers no)
		(fp_line
			(start -0.7874 0.4064)
			(end 0.7874 0.4064)
			(stroke
				(width 0.1524)
				(type default)
			)
			(layer "B.SilkS")
		)
		(fp_line
			(start 0.7874 0.4064)
			(end 0.7874 -0.4064)
			(stroke
				(width 0.1524)
				(type default)
			)
			(layer "B.SilkS")
		)
		(fp_line
			(start -0.7874 -0.4064)
			(end -0.7874 0.4064)
			(stroke
				(width 0.1524)
				(type default)
			)
			(layer "B.SilkS")
		)
		(fp_line
			(start 0.7874 -0.4064)
			(end -0.7874 -0.4064)
			(stroke
				(width 0.1524)
				(type default)
			)
			(layer "B.SilkS")
		)
		(fp_line
			(start -0.67945 0.3048)
			(end -0.120396 0.3048)
			(stroke
				(width 0.1)
				(type default)
			)
			(layer "B.Fab")
		)
		(fp_line
			(start -0.120396 0.3048)
			(end -0.120396 0.2794)
			(stroke
				(width 0.1)
				(type default)
			)
			(layer "B.Fab")
		)
		(fp_line
			(start 0.12065 0.3048)
			(end 0.67945 0.3048)
			(stroke
				(width 0.1)
				(type default)
			)
			(layer "B.Fab")
		)
		(fp_line
			(start 0.67945 0.3048)
			(end 0.67945 -0.305054)
			(stroke
				(width 0.1)
				(type default)
			)
			(layer "B.Fab")
		)
		(fp_line
			(start -0.120396 0.2794)
			(end 0.12065 0.2794)
			(stroke
				(width 0.1)
				(type default)
			)
			(layer "B.Fab")
		)
		(fp_line
			(start 0.12065 0.2794)
			(end 0.12065 0.3048)
			(stroke
				(width 0.1)
				(type default)
			)
			(layer "B.Fab")
		)
		(fp_line
			(start -0.12065 -0.2794)
			(end -0.12065 -0.3048)
			(stroke
				(width 0.1)
				(type default)
			)
			(layer "B.Fab")
		)
		(fp_line
			(start 0.12065 -0.2794)
			(end -0.12065 -0.2794)
			(stroke
				(width 0.1)
				(type default)
			)
			(layer "B.Fab")
		)
		(fp_line
			(start -0.67945 -0.3048)
			(end -0.67945 0.3048)
			(stroke
				(width 0.1)
				(type default)
			)
			(layer "B.Fab")
		)
		(fp_line
			(start -0.12065 -0.3048)
			(end -0.67945 -0.3048)
			(stroke
				(width 0.1)
				(type default)
			)
			(layer "B.Fab")
		)
		(fp_line
			(start 0.12065 -0.305054)
			(end 0.12065 -0.2794)
			(stroke
				(width 0.1)
				(type default)
			)
			(layer "B.Fab")
		)
		(fp_line
			(start 0.67945 -0.305054)
			(end 0.12065 -0.305054)
			(stroke
				(width 0.1)
				(type default)
			)
			(layer "B.Fab")
		)
		(pad "1" smd circle
			(at 0.40005 0 90)
			(size 0 0)
			(layers "B.Cu" "B.Mask" "B.Paste")
			(net "P1V2_P1V0_I3C_VDDL1")
		)
		(pad "2" smd circle
			(at -0.40005 0 90)
			(size 0 0)
			(layers "B.Cu" "B.Mask" "B.Paste")
			(net "I3C1_SPD_SDA")
		)
	)
)
